# BASEBOARD_FAB2 (Tioga Pass) — schematic netlist excerpt (pin names and nets, part order shuffled) for the footprints in the layout excerpt that follows; sources: Cadence DE-HDL packaged netlist, KiCad conversion of Wiwynn_Tioga_Pass_MB.brd

C2G1  CAP_A  47UF 4V 20% X5R  pkg 0603V  page 225 : A = PVDDQ_GHJ ; B = GND
C6F4  CAPP  330UF 6.3V 20% POSCAP  pkg 7343LF  page 231 : A = PVPP_ABC ; B = GND
R7A19  RES  10.0 1% CHIP  pkg 0402  page 236 : A = VSENSE_PVNN_PCH_STBY_QAT ; B = VSENSE_PVNN_PCH_STBY_AVSP

(kicad_pcb
	(version 20260206)
	(generator "pcbnew")
	(generator_version "10.0")
	(general
		(thickness 1.6)
		(legacy_teardrops no)
	)
	(paper "A4")
	(title_block
		(title "Wiwynn_Tioga_Pass_MB.brd")
		(comment 1 "Tioga Pass / footprints 334-336 of 4770")
	)
	(layers
		(0 "F.Cu" signal "TOP")
		(4 "In1.Cu" signal "L2GND")
		(6 "In2.Cu" signal "L3")
		(8 "In3.Cu" signal "L4GND")
		(10 "In4.Cu" signal "L5")
		(12 "In5.Cu" signal "L6GND")
		(14 "In6.Cu" signal "L7VCC")
		(16 "In7.Cu" signal "L8VCC")
		(18 "In8.Cu" signal "L9GND")
		(20 "In9.Cu" signal "L10")
		(22 "In10.Cu" signal "L11GND")
		(24 "In11.Cu" signal "L12")
		(26 "In12.Cu" signal "L13GND")
		(2 "B.Cu" signal "BOTTOM")
		(9 "F.Adhes" user "F.Adhesive")
		(11 "B.Adhes" user "B.Adhesive")
		(13 "F.Paste" user "Package Geometry/Pastemask Top")
		(15 "B.Paste" user "Package Geometry/Pastemask Bottom")
		(5 "F.SilkS" user "Ref Des/Silkscreen Top")
		(7 "B.SilkS" user "Ref Des/Silkscreen Bottom")
		(1 "F.Mask" user "Board Geometry/Soldermask Top")
		(3 "B.Mask" user "Board Geometry/Soldermask Bottom")
		(17 "Dwgs.User" user "User.Drawings")
		(19 "Cmts.User" user "User.Comments")
		(21 "Eco1.User" user "User.Eco1")
		(23 "Eco2.User" user "User.Eco2")
		(25 "Edge.Cuts" user "Board Geometry/Outline")
		(27 "Margin" user)
		(31 "F.CrtYd" user "Package Geometry/Place Bound Top")
		(29 "B.CrtYd" user "Package Geometry/Place Bound Bottom")
		(35 "F.Fab" user "Ref Des/Assembly Top")
		(33 "B.Fab" user "Ref Des/Assembly Bottom")
	)
	(footprint ""
		(layer "F.Cu")
		(at 328.9808 -26.6827 180)
		(property "Reference" "C6F4"
			(at 2.91973 -1.9812 90)
			(unlocked yes)
			(layer "F.SilkS")
			(effects
				(font
					(size 0.7874 0.5842)
					(thickness 0.1524)
				)
				(justify left)
			)
		)
		(property "Value" ""
			(at 0 0 180)
			(layer "F.Fab")
			(effects
				(font
					(size 1.27 1.27)
				)
			)
		)
		(duplicate_pad_numbers_are_jumpers no)
		(fp_line
			(start 2.2987 7.3533)
			(end 2.2987 -0.2413)
			(stroke
				(width 0.1524)
				(type default)
			)
			(layer "F.SilkS")
		)
		(fp_line
			(start 2.2987 -0.2413)
			(end 2.032 -0.2413)
			(stroke
				(width 0.1524)
				(type default)
			)
			(layer "F.SilkS")
		)
		(fp_line
			(start 2.032 1.524)
			(end 1.7272 1.524)
			(stroke
				(width 0.1524)
				(type default)
			)
			(layer "F.SilkS")
		)
		(fp_line
			(start 2.032 -1.524)
			(end 2.032 1.524)
			(stroke
				(width 0.1524)
				(type default)
			)
			(layer "F.SilkS")
		)
		(fp_line
			(start 1.7272 7.3533)
			(end 2.2987 7.3533)
			(stroke
				(width 0.1524)
				(type default)
			)
			(layer "F.SilkS")
		)
		(fp_line
			(start 1.7272 -1.524)
			(end 2.032 -1.524)
			(stroke
				(width 0.1524)
				(type default)
			)
			(layer "F.SilkS")
		)
		(fp_line
			(start -1.7272 -1.524)
			(end -2.032 -1.524)
			(stroke
				(width 0.1524)
				(type default)
			)
			(layer "F.SilkS")
		)
		(fp_line
			(start -2.032 1.524)
			(end -1.7272 1.524)
			(stroke
				(width 0.1524)
				(type default)
			)
			(layer "F.SilkS")
		)
		(fp_line
			(start -2.032 -0.2413)
			(end -2.2987 -0.2413)
			(stroke
				(width 0.1524)
				(type default)
			)
			(layer "F.SilkS")
		)
		(fp_line
			(start -2.032 -1.524)
			(end -2.032 1.524)
			(stroke
				(width 0.1524)
				(type default)
			)
			(layer "F.SilkS")
		)
		(fp_line
			(start -2.2987 7.3533)
			(end -1.7272 7.3533)
			(stroke
				(width 0.1524)
				(type default)
			)
			(layer "F.SilkS")
		)
		(fp_line
			(start -2.2987 -0.2413)
			(end -2.2987 7.3533)
			(stroke
				(width 0.1524)
				(type default)
			)
			(layer "F.SilkS")
		)
		(fp_rect
			(start 2.2987 -0.2413)
			(end -2.2987 7.3533)
			(stroke
				(width 0)
				(type default)
			)
			(fill no)
			(layer "F.CrtYd")
		)
		(fp_line
			(start 2.2987 7.3533)
			(end -2.2987 7.3533)
			(stroke
				(width 0.1)
				(type default)
			)
			(layer "F.Fab")
		)
		(fp_line
			(start 2.2987 -0.2413)
			(end 2.2987 7.3533)
			(stroke
				(width 0.1)
				(type default)
			)
			(layer "F.Fab")
		)
		(fp_line
			(start -2.2987 7.3533)
			(end -2.2987 -0.2413)
			(stroke
				(width 0.1)
				(type default)
			)
			(layer "F.Fab")
		)
		(fp_line
			(start -2.2987 -0.2413)
			(end 2.2987 -0.2413)
			(stroke
				(width 0.1)
				(type default)
			)
			(layer "F.Fab")
		)
		(pad "1" smd rect
			(at 0 0 180)
			(size 2.54 3.048)
			(layers "F.Cu" "F.Mask" "F.Paste")
			(net "PVPP_ABC")
		)
		(pad "2" smd rect
			(at 0 7.112 180)
			(size 2.54 3.048)
			(layers "F.Cu" "F.Mask" "F.Paste")
			(net "GND")
		)
	)
	(footprint ""
		(layer "F.Cu")
		(at 369.57 -136.4615 180)
		(property "Reference" "R7A19"
			(at 0 0 180)
			(layer "F.SilkS")
			(hide yes)
			(effects
				(font
					(size 1.27 1.27)
				)
			)
		)
		(property "Value" ""
			(at 0 0 180)
			(layer "F.Fab")
			(effects
				(font
					(size 1.27 1.27)
				)
			)
		)
		(duplicate_pad_numbers_are_jumpers no)
		(fp_poly
			(pts
				(xy -0.2794 -0.1016) (xy 0.2794 -0.1016) (xy 0.2794 0.9906) (xy -0.2794 0.9906)
			)
			(stroke
				(width 0)
				(type default)
			)
			(fill no)
			(layer "F.CrtYd")
		)
		(fp_line
			(start 0.2794 0.9906)
			(end 0.2794 -0.1016)
			(stroke
				(width 0.1)
				(type default)
			)
			(layer "F.Fab")
		)
		(fp_line
			(start 0.2794 -0.1016)
			(end -0.2794 -0.1016)
			(stroke
				(width 0.1)
				(type default)
			)
			(layer "F.Fab")
		)
		(fp_line
			(start -0.2794 0.9906)
			(end 0.2794 0.9906)
			(stroke
				(width 0.1)
				(type default)
			)
			(layer "F.Fab")
		)
		(fp_line
			(start -0.2794 -0.1016)
			(end -0.2794 0.9906)
			(stroke
				(width 0.1)
				(type default)
			)
			(layer "F.Fab")
		)
		(pad "1" smd rect
			(at 0 0 180)
			(size 0.508 0.508)
			(layers "F.Cu" "F.Mask" "F.Paste")
			(net "VSENSE_PVNN_PCH_STBY_QAT")
		)
		(pad "2" smd rect
			(at 0 0.889 180)
			(size 0.508 0.508)
			(layers "F.Cu" "F.Mask" "F.Paste")
			(net "VSENSE_PVNN_PCH_STBY_AVSP")
		)
		(zone
			(layer "F.Cu")
			(hatch none 0.5)
			(connect_pads
				(clearance 0)
			)
			(min_thickness 0.25)
			(keepout
				(tracks not_allowed)
				(vias allowed)
				(pads allowed)
				(copperpour not_allowed)
				(footprints allowed)
			)
			(placement
				(enabled no)
				(sheetname "")
			)
			(fill
				(thermal_gap 0.5)
				(thermal_bridge_width 0.5)
				(island_removal_mode 0)
			)
			(polygon
				(pts
					(xy 369.824 -137.0965) (xy 369.316 -137.0965) (xy 369.316 -136.7155) (xy 369.824 -136.7155)
				)
			)
		)
		(zone
			(layer "F.Cu")
			(hatch none 0.5)
			(connect_pads
				(clearance 0)
			)
			(min_thickness 0.25)
			(keepout
				(tracks allowed)
				(vias not_allowed)
				(pads allowed)
				(copperpour not_allowed)
				(footprints allowed)
			)
			(placement
				(enabled no)
				(sheetname "")
			)
			(fill
				(thermal_gap 0.5)
				(thermal_bridge_width 0.5)
				(island_removal_mode 0)
			)
			(polygon
				(pts
					(xy 369.824 -136.7155) (xy 369.316 -136.7155) (xy 369.316 -137.0965) (xy 369.824 -137.0965)
				)
			)
		)
	)
	(footprint ""
		(layer "F.Cu")
		(at 80.757268 -12.954 -90)
		(property "Reference" "C2G1"
			(at 1.848866 0.752348 270)
			(unlocked yes)
			(layer "F.SilkS")
			(effects
				(font
					(size 1.27 0.9652)
					(thickness 0.1524)
				)
			)
		)
		(property "Value" ""
			(at 0 0 270)
			(layer "F.Fab")
			(effects
				(font
					(size 1.27 1.27)
				)
			)
		)
		(duplicate_pad_numbers_are_jumpers no)
		(fp_rect
			(start -0.500126 1.598422)
			(end 0.500126 -0.201422)
			(stroke
				(width 0)
				(type default)
			)
			(fill no)
			(layer "F.CrtYd")
		)
		(fp_line
			(start -0.500126 1.598422)
			(end -0.500126 -0.201422)
			(stroke
				(width 0.1)
				(type default)
			)
			(layer "F.Fab")
		)
		(fp_line
			(start 0.500126 1.598422)
			(end -0.500126 1.598422)
			(stroke
				(width 0.1)
				(type default)
			)
			(layer "F.Fab")
		)
		(fp_line
			(start -0.500126 -0.201422)
			(end 0.500126 -0.201422)
			(stroke
				(width 0.1)
				(type default)
			)
			(layer "F.Fab")
		)
		(fp_line
			(start 0.500126 -0.201422)
			(end 0.500126 1.598422)
			(stroke
				(width 0.1)
				(type default)
			)
			(layer "F.Fab")
		)
		(pad "1" smd rect
			(at 0 0 180)
			(size 0.889 0.9906)
			(layers "F.Cu" "F.Mask" "F.Paste")
			(net "PVDDQ_GHJ")
		)
		(pad "2" smd rect
			(at 0 1.397 180)
			(size 0.889 0.9906)
			(layers "F.Cu" "F.Mask" "F.Paste")
			(net "GND")
		)
		(zone
			(layer "F.Cu")
			(hatch none 0.5)
			(connect_pads
				(clearance 0)
			)
			(min_thickness 0.25)
			(keepout
				(tracks allowed)
				(vias not_allowed)
				(pads allowed)
				(copperpour not_allowed)
				(footprints allowed)
			)
			(placement
				(enabled no)
				(sheetname "")
			)
			(fill
				(thermal_gap 0.5)
				(thermal_bridge_width 0.5)
				(island_removal_mode 0)
			)
			(polygon
				(pts
					(xy 79.804768 -13.4493) (xy 79.804768 -12.4587) (xy 80.312768 -12.4587) (xy 80.312768 -13.4493)
				)
			)
		)
		(zone
			(layer "F.Cu")
			(hatch none 0.5)
			(connect_pads
				(clearance 0)
			)
			(min_thickness 0.25)
			(keepout
				(tracks not_allowed)
				(vias allowed)
				(pads allowed)
				(copperpour not_allowed)
				(footprints allowed)
			)
			(placement
				(enabled no)
				(sheetname "")
			)
			(fill
				(thermal_gap 0.5)
				(thermal_bridge_width 0.5)
				(island_removal_mode 0)
			)
			(polygon
				(pts
					(xy 79.804768 -13.4493) (xy 79.804768 -12.4587) (xy 80.312768 -12.4587) (xy 80.312768 -13.4493)
				)
			)
		)
	)
)
